(kicad_pcb
	(version 20260206)
	(generator "pcbnew")
	(generator_version "10.0")
	(general
		(thickness 1.6)
		(legacy_teardrops no)
	)
	(paper "A4")
	(title_block
		(title "01162023_DA0F0TEBIF0_F0T_Expander_BD_F_brd_V02_OCP.brd")
		(comment 1 "Grand Teton / footprints 6955-6956 of 9728")
	)
	(layers
		(0 "F.Cu" signal "TOP")
		(4 "In1.Cu" signal "GND")
		(6 "In2.Cu" signal "VCC")
		(8 "In3.Cu" signal "VCC1")
		(10 "In4.Cu" signal "GND1")
		(12 "In5.Cu" signal "IN1")
		(14 "In6.Cu" signal "GND2")
		(16 "In7.Cu" signal "IN2")
		(18 "In8.Cu" signal "GND3")
		(20 "In9.Cu" signal "IN3")
		(22 "In10.Cu" signal "GND4")
		(24 "In11.Cu" signal "IN4")
		(26 "In12.Cu" signal "GND5")
		(28 "In13.Cu" signal "IN5")
		(30 "In14.Cu" signal "GND6")
		(32 "In15.Cu" signal "IN6")
		(34 "In16.Cu" signal "GND7")
		(2 "B.Cu" signal "BOTTOM")
		(9 "F.Adhes" user "F.Adhesive")
		(11 "B.Adhes" user "B.Adhesive")
		(13 "F.Paste" user "Package Geometry/Pastemask Top")
		(15 "B.Paste" user "Package Geometry/Pastemask Bottom")
		(5 "F.SilkS" user "Ref Des/Silkscreen Top")
		(7 "B.SilkS" user "Ref Des/Silkscreen Bottom")
		(1 "F.Mask" user "Board Geometry/Soldermask Top")
		(3 "B.Mask" user "Board Geometry/Soldermask Bottom")
		(17 "Dwgs.User" user "User.Drawings")
		(19 "Cmts.User" user "User.Comments")
		(21 "Eco1.User" user "User.Eco1")
		(23 "Eco2.User" user "User.Eco2")
		(25 "Edge.Cuts" user "Board Geometry/Outline")
		(27 "Margin" user)
		(31 "F.CrtYd" user "Package Geometry/Place Bound Top")
		(29 "B.CrtYd" user "Package Geometry/Place Bound Bottom")
		(35 "F.Fab" user "Ref Des/Assembly Top")
		(33 "B.Fab" user "Ref Des/Assembly Bottom")
	)
	(footprint ""
		(layer "F.Cu")
		(at 352.975926 -258.394962 90)
		(property "Reference" "PU11"
			(at -2.542794 -6.725158 90)
			(unlocked yes)
			(layer "F.SilkS")
			(effects
				(font
					(size 0.7874 0.5842)
					(thickness 0.1524)
				)
				(justify left)
			)
		)
		(property "Value" ""
			(at 0 0 90)
			(layer "F.Fab")
			(effects
				(font
					(size 1.27 1.27)
				)
			)
		)
		(duplicate_pad_numbers_are_jumpers no)
		(fp_line
			(start 0.1778 -3.2385)
			(end 0.1778 -2.8575)
			(stroke
				(width 0.1524)
				(type default)
			)
			(layer "F.SilkS")
		)
		(fp_line
			(start -1.8034 -2.8702)
			(end -1.8034 -3.6322)
			(stroke
				(width 0.1524)
				(type default)
			)
			(layer "F.SilkS")
		)
		(fp_line
			(start 2.500122 -2.500122)
			(end 2.500122 -2.015998)
			(stroke
				(width 0.1524)
				(type default)
			)
			(layer "F.SilkS")
		)
		(fp_line
			(start 2.015998 -2.500122)
			(end 2.500122 -2.500122)
			(stroke
				(width 0.1524)
				(type default)
			)
			(layer "F.SilkS")
		)
		(fp_line
			(start -2.500122 -2.500122)
			(end -2.015998 -2.500122)
			(stroke
				(width 0.1524)
				(type default)
			)
			(layer "F.SilkS")
		)
		(fp_line
			(start -2.500122 -2.015998)
			(end -2.500122 -2.500122)
			(stroke
				(width 0.1524)
				(type default)
			)
			(layer "F.SilkS")
		)
		(fp_line
			(start 2.8702 -1.778)
			(end 3.6322 -1.778)
			(stroke
				(width 0.1524)
				(type default)
			)
			(layer "F.SilkS")
		)
		(fp_line
			(start -3.2639 -0.1778)
			(end -2.8829 -0.1778)
			(stroke
				(width 0.1524)
				(type default)
			)
			(layer "F.SilkS")
		)
		(fp_line
			(start 2.8829 0.2032)
			(end 3.2639 0.2032)
			(stroke
				(width 0.1524)
				(type default)
			)
			(layer "F.SilkS")
		)
		(fp_line
			(start -3.6576 1.8034)
			(end -2.8956 1.8034)
			(stroke
				(width 0.1524)
				(type default)
			)
			(layer "F.SilkS")
		)
		(fp_line
			(start 2.500122 2.015998)
			(end 2.500122 2.500122)
			(stroke
				(width 0.1524)
				(type default)
			)
			(layer "F.SilkS")
		)
		(fp_line
			(start 2.500122 2.500122)
			(end 2.015998 2.500122)
			(stroke
				(width 0.1524)
				(type default)
			)
			(layer "F.SilkS")
		)
		(fp_line
			(start -2.015998 2.500122)
			(end -2.500122 2.500122)
			(stroke
				(width 0.1524)
				(type default)
			)
			(layer "F.SilkS")
		)
		(fp_line
			(start -2.500122 2.500122)
			(end -2.500122 2.018538)
			(stroke
				(width 0.1524)
				(type default)
			)
			(layer "F.SilkS")
		)
		(fp_line
			(start -0.2032 2.8829)
			(end -0.2032 3.2639)
			(stroke
				(width 0.1524)
				(type default)
			)
			(layer "F.SilkS")
		)
		(fp_line
			(start 1.778 3.6322)
			(end 1.778 2.8702)
			(stroke
				(width 0.1524)
				(type default)
			)
			(layer "F.SilkS")
		)
		(fp_poly
			(pts
				(xy -2.921 -1.800098) (xy -3.504184 -1.508506) (xy -3.504184 -2.09169)
			)
			(stroke
				(width 0)
				(type default)
			)
			(fill yes)
			(layer "F.SilkS")
		)
		(fp_line
			(start 0.1778 -3.2385)
			(end 0.1778 -2.8575)
			(stroke
				(width 0.1)
				(type default)
			)
			(layer "F.Fab")
		)
		(fp_line
			(start -1.8034 -2.8702)
			(end -1.8034 -3.6322)
			(stroke
				(width 0.1)
				(type default)
			)
			(layer "F.Fab")
		)
		(fp_line
			(start 2.500122 -2.500122)
			(end 2.500122 2.500122)
			(stroke
				(width 0.1)
				(type default)
			)
			(layer "F.Fab")
		)
		(fp_line
			(start -2.500122 -2.500122)
			(end 2.500122 -2.500122)
			(stroke
				(width 0.1)
				(type default)
			)
			(layer "F.Fab")
		)
		(fp_line
			(start 2.8702 -1.778)
			(end 3.6322 -1.778)
			(stroke
				(width 0.1)
				(type default)
			)
			(layer "F.Fab")
		)
		(fp_line
			(start -3.2639 -0.1778)
			(end -2.8829 -0.1778)
			(stroke
				(width 0.1)
				(type default)
			)
			(layer "F.Fab")
		)
		(fp_line
			(start 2.8829 0.2032)
			(end 3.2639 0.2032)
			(stroke
				(width 0.1)
				(type default)
			)
			(layer "F.Fab")
		)
		(fp_line
			(start -3.6576 1.8034)
			(end -2.8956 1.8034)
			(stroke
				(width 0.1)
				(type default)
			)
			(layer "F.Fab")
		)
		(fp_line
			(start 2.500122 2.500122)
			(end -2.500122 2.500122)
			(stroke
				(width 0.1)
				(type default)
			)
			(layer "F.Fab")
		)
		(fp_line
			(start -2.500122 2.500122)
			(end -2.500122 -2.500122)
			(stroke
				(width 0.1)
				(type default)
			)
			(layer "F.Fab")
		)
		(fp_line
			(start -0.2032 2.8829)
			(end -0.2032 3.2639)
			(stroke
				(width 0.1)
				(type default)
			)
			(layer "F.Fab")
		)
		(fp_line
			(start 1.778 3.6322)
			(end 1.778 2.8702)
			(stroke
				(width 0.1)
				(type default)
			)
			(layer "F.Fab")
		)
		(fp_poly
			(pts
				(xy -2.921 -1.800098) (xy -3.504184 -1.508506) (xy -3.504184 -2.09169)
			)
			(stroke
				(width 0)
				(type default)
			)
			(fill yes)
			(layer "F.Fab")
		)
		(fp_text user "31"
			(at 0.4318 -3.336036 90)
			(unlocked yes)
			(layer "F.SilkS")
			(effects
				(font
					(size 0.635 0.4064)
					(thickness 0.1524)
				)
				(justify left)
			)
		)
		(fp_text user "30"
			(at 3.223768 -3.0988 0)
			(unlocked yes)
			(layer "F.SilkS")
			(effects
				(font
					(size 0.635 0.4064)
					(thickness 0.1524)
				)
				(justify left)
			)
		)
		(fp_text user "40"
			(at -3.2004 -3.096768 90)
			(unlocked yes)
			(layer "F.SilkS")
			(effects
				(font
					(size 0.635 0.4064)
					(thickness 0.1524)
				)
				(justify left)
			)
		)
		(fp_text user "21"
			(at 3.208782 0.362712 0)
			(unlocked yes)
			(layer "F.SilkS")
			(effects
				(font
					(size 0.635 0.4064)
					(thickness 0.1524)
				)
				(justify left)
			)
		)
		(fp_text user "10"
			(at -3.253232 2.1336 0)
			(unlocked yes)
			(layer "F.SilkS")
			(effects
				(font
					(size 0.635 0.4064)
					(thickness 0.1524)
				)
				(justify left)
			)
		)
		(fp_text user "11"
			(at -2.51206 3.269234 90)
			(unlocked yes)
			(layer "F.SilkS")
			(effects
				(font
					(size 0.635 0.4064)
					(thickness 0.1524)
				)
				(justify left)
			)
		)
		(fp_text user "20"
			(at 0.911352 5.261102 90)
			(unlocked yes)
			(layer "F.SilkS")
			(effects
				(font
					(size 0.635 0.4064)
					(thickness 0.1524)
				)
				(justify left)
			)
		)
		(fp_text user "31"
			(at 1.8542 -3.172968 90)
			(unlocked yes)
			(layer "F.Fab")
			(effects
				(font
					(size 0.635 0.4064)
					(thickness 0.1524)
				)
				(justify left)
			)
		)
		(fp_text user "30"
			(at 3.223768 -3.0988 0)
			(unlocked yes)
			(layer "F.Fab")
			(effects
				(font
					(size 0.635 0.4064)
					(thickness 0.1524)
				)
				(justify left)
			)
		)
		(fp_text user "40"
			(at -3.2004 -3.096768 90)
			(unlocked yes)
			(layer "F.Fab")
			(effects
				(font
					(size 0.635 0.4064)
					(thickness 0.1524)
				)
				(justify left)
			)
		)
		(fp_text user "21"
			(at 3.274568 1.8796 0)
			(unlocked yes)
			(layer "F.Fab")
			(effects
				(font
					(size 0.635 0.4064)
					(thickness 0.1524)
				)
				(justify left)
			)
		)
		(fp_text user "10"
			(at -3.253232 2.1336 0)
			(unlocked yes)
			(layer "F.Fab")
			(effects
				(font
					(size 0.635 0.4064)
					(thickness 0.1524)
				)
				(justify left)
			)
		)
		(fp_text user "20"
			(at 2.0828 3.253232 90)
			(unlocked yes)
			(layer "F.Fab")
			(effects
				(font
					(size 0.635 0.4064)
					(thickness 0.1524)
				)
				(justify left)
			)
		)
		(fp_text user "11"
			(at -2.8702 3.278632 90)
			(unlocked yes)
			(layer "F.Fab")
			(effects
				(font
					(size 0.635 0.4064)
					(thickness 0.1524)
				)
				(justify left)
			)
		)
		(pad "1" smd rect
			(at -2.400046 -1.800098)
			(size 0.1778 0.6096)
			(layers "F.Cu" "F.Mask" "F.Paste")
			(net "P0V8_PEX3_PWM1")
		)
		(pad "2" smd rect
			(at -2.400046 -1.400048)
			(size 0.1778 0.6096)
			(layers "F.Cu" "F.Mask" "F.Paste")
			(net "P0V8_PEX3_PWM2")
		)
		(pad "3" smd rect
			(at -2.400046 -0.999998)
			(size 0.1778 0.6096)
			(layers "F.Cu" "F.Mask" "F.Paste")
			(net "NC_P0V8_PEX2_PWM3")
		)
		(pad "4" smd rect
			(at -2.400046 -0.599948)
			(size 0.1778 0.6096)
			(layers "F.Cu" "F.Mask" "F.Paste")
			(net "NC_P0V8_PEX2_PWM4")
		)
		(pad "5" smd rect
			(at -2.400046 -0.199898)
			(size 0.1778 0.6096)
			(layers "F.Cu" "F.Mask" "F.Paste")
			(net "NC_P0V8_PEX2_PWM5")
		)
		(pad "6" smd rect
			(at -2.400046 0.199898)
			(size 0.1778 0.6096)
			(layers "F.Cu" "F.Mask" "F.Paste")
			(net "NC_P0V8_PEX2_PWM6")
		)
		(pad "7" smd rect
			(at -2.400046 0.599948)
			(size 0.1778 0.6096)
			(layers "F.Cu" "F.Mask" "F.Paste")
			(net "P0V8_PEX2_PWM2")
		)
		(pad "8" smd rect
			(at -2.400046 0.999998)
			(size 0.1778 0.6096)
			(layers "F.Cu" "F.Mask" "F.Paste")
			(net "P0V8_PEX2_PWM1")
		)
		(pad "9" smd rect
			(at -2.400046 1.400048)
			(size 0.1778 0.6096)
			(layers "F.Cu" "F.Mask" "F.Paste")
			(net "SMB_VR_P0V8_PEX2_SDA")
		)
		(pad "10" smd rect
			(at -2.400046 1.800098)
			(size 0.1778 0.6096)
			(layers "F.Cu" "F.Mask" "F.Paste")
			(net "SMB_VR_P0V8_PEX2_SCL")
		)
		(pad "11" smd rect
			(at -1.800098 2.400046 90)
			(size 0.1778 0.6096)
			(layers "F.Cu" "F.Mask" "F.Paste")
			(net "P0V8_PEX2_SMBALERT")
		)
		(pad "12" smd rect
			(at -1.400048 2.400046 90)
			(size 0.1778 0.6096)
			(layers "F.Cu" "F.Mask" "F.Paste")
			(net "P0V8_PEX2_AVRRDY")
		)
		(pad "13" smd rect
			(at -0.999998 2.400046 90)
			(size 0.1778 0.6096)
			(layers "F.Cu" "F.Mask" "F.Paste")
			(net "FM_P0V8_PEX2_EN_R")
		)
		(pad "14" smd rect
			(at -0.599948 2.400046 90)
			(size 0.1778 0.6096)
			(layers "F.Cu" "F.Mask" "F.Paste")
			(net "P0V8_PEX2_VRHOT_R")
		)
		(pad "15" smd rect
			(at -0.199898 2.400046 90)
			(size 0.1778 0.6096)
			(layers "F.Cu" "F.Mask" "F.Paste")
			(net "P0V8_PEX2_PINALRT")
		)
		(pad "16" smd rect
			(at 0.199898 2.400046 90)
			(size 0.1778 0.6096)
			(layers "F.Cu" "F.Mask" "F.Paste")
			(net "P0V8_PEX3_BVRRDY")
		)
		(pad "17" smd rect
			(at 0.599948 2.400046 90)
			(size 0.1778 0.6096)
			(layers "F.Cu" "F.Mask" "F.Paste")
			(net "P0V8_PEX2_SVID")
		)
		(pad "18" smd rect
			(at 0.999998 2.400046 90)
			(size 0.1778 0.6096)
			(layers "F.Cu" "F.Mask" "F.Paste")
			(net "P0V8_PEX2_SVID")
		)
		(pad "19" smd rect
			(at 1.400048 2.400046 90)
			(size 0.1778 0.6096)
			(layers "F.Cu" "F.Mask" "F.Paste")
			(net "NC_P0V8_PEX2_SVID_ALERT_N_R")
		)
		(pad "20" smd rect
			(at 1.800098 2.400046 90)
			(size 0.1778 0.6096)
			(layers "F.Cu" "F.Mask" "F.Paste")
			(net "FM_P0V8_PEX3_EN_R")
		)
		(pad "21" smd rect
			(at 2.400046 1.800098)
			(size 0.1778 0.6096)
			(layers "F.Cu" "F.Mask" "F.Paste")
			(net "P0V8_PEX2_VSEN2")
		)
		(pad "22" smd rect
			(at 2.400046 1.400048)
			(size 0.1778 0.6096)
			(layers "F.Cu" "F.Mask" "F.Paste")
			(net "SH_P0V8_PEX2_RGND2")
		)
		(pad "23" smd rect
			(at 2.400046 0.999998)
			(size 0.1778 0.6096)
			(layers "F.Cu" "F.Mask" "F.Paste")
			(net "P0V8_PEX2_ISEN1")
		)
		(pad "24" smd rect
			(at 2.400046 0.599948)
			(size 0.1778 0.6096)
			(layers "F.Cu" "F.Mask" "F.Paste")
			(net "P0V8_PEX2_ISEN2")
		)
		(pad "25" smd rect
			(at 2.400046 0.199898)
			(size 0.1778 0.6096)
			(layers "F.Cu" "F.Mask" "F.Paste")
			(net "NC_P0V8_PEX2_ISEN6")
		)
		(pad "26" smd rect
			(at 2.400046 -0.199898)
			(size 0.1778 0.6096)
			(layers "F.Cu" "F.Mask" "F.Paste")
			(net "NC_P0V8_PEX2_ISEN5")
		)
		(pad "27" smd rect
			(at 2.400046 -0.599948)
			(size 0.1778 0.6096)
			(layers "F.Cu" "F.Mask" "F.Paste")
			(net "NC_P0V8_PEX2_ISEN4")
		)
		(pad "28" smd rect
			(at 2.400046 -0.999998)
			(size 0.1778 0.6096)
			(layers "F.Cu" "F.Mask" "F.Paste")
			(net "NC_P0V8_PEX2_ISEN3")
		)
		(pad "29" smd rect
			(at 2.400046 -1.400048)
			(size 0.1778 0.6096)
			(layers "F.Cu" "F.Mask" "F.Paste")
			(net "P0V8_PEX3_ISEN2")
		)
		(pad "30" smd rect
			(at 2.400046 -1.800098)
			(size 0.1778 0.6096)
			(layers "F.Cu" "F.Mask" "F.Paste")
			(net "P0V8_PEX3_ISEN1")
		)
		(pad "31" smd rect
			(at 1.800098 -2.400046 90)
			(size 0.1778 0.6096)
			(layers "F.Cu" "F.Mask" "F.Paste")
			(net "SH_P0V8_PEX3_RGND3")
		)
		(pad "32" smd rect
			(at 1.400048 -2.400046 90)
			(size 0.1778 0.6096)
			(layers "F.Cu" "F.Mask" "F.Paste")
			(net "P0V8_PEX3_VSEN3")
		)
		(pad "33" smd rect
			(at 0.999998 -2.400046 90)
			(size 0.1778 0.6096)
			(layers "F.Cu" "F.Mask" "F.Paste")
			(net "P0V8_PEX2_VR_CONFIG")
		)
		(pad "34" smd rect
			(at 0.599948 -2.400046 90)
			(size 0.1778 0.6096)
			(layers "F.Cu" "F.Mask" "F.Paste")
			(net "P0V8_PEX2_ADDR")
		)
		(pad "35" smd rect
			(at 0.199898 -2.400046 90)
			(size 0.1778 0.6096)
			(layers "F.Cu" "F.Mask" "F.Paste")
			(net "P0V8_PEX2_TSEN_R")
		)
		(pad "36" smd rect
			(at -0.199898 -2.400046 90)
			(size 0.1778 0.6096)
			(layers "F.Cu" "F.Mask" "F.Paste")
			(net "P0V8_PEX3_TSEN_R")
		)
		(pad "37" smd rect
			(at -0.599948 -2.400046 90)
			(size 0.1778 0.6096)
			(layers "F.Cu" "F.Mask" "F.Paste")
			(net "P0V8_PEX2_IINSEN")
		)
		(pad "38" smd rect
			(at -0.999998 -2.400046 90)
			(size 0.1778 0.6096)
			(layers "F.Cu" "F.Mask" "F.Paste")
			(net "P0V8_PEX2_VINSEN")
		)
		(pad "39" smd rect
			(at -1.400048 -2.400046 90)
			(size 0.1778 0.6096)
			(layers "F.Cu" "F.Mask" "F.Paste")
			(net "P0V8_PEX2_VDD")
		)
		(pad "40" smd rect
			(at -1.800098 -2.400046 90)
			(size 0.1778 0.6096)
			(layers "F.Cu" "F.Mask" "F.Paste")
			(net "P0V8_PEX2_VREF")
		)
		(pad "TH" smd rect
			(at 0 0 90)
			(size 3.6576 3.6576)
			(layers "F.Cu" "F.Mask" "F.Paste")
			(net "GND")
		)
		(zone
			(layer "F.Cu")
			(hatch none 0.5)
			(connect_pads
				(clearance 0)
			)
			(min_thickness 0.25)
			(keepout
				(tracks not_allowed)
				(vias allowed)
				(pads allowed)
				(copperpour not_allowed)
				(footprints allowed)
			)
			(placement
				(enabled no)
				(sheetname "")
			)
			(fill
				(thermal_gap 0.5)
				(thermal_bridge_width 0.5)
				(island_removal_mode 0)
			)
			(polygon
				(pts
					(xy 350.943926 -256.362962) (xy 350.943926 -260.426962) (xy 355.007926 -260.426962) (xy 355.007926 -256.362962)
					(xy 351.121726 -256.362962) (xy 351.121726 -256.515362) (xy 354.855526 -256.515362) (xy 354.855526 -260.274562)
					(xy 351.096326 -260.274562) (xy 351.096326 -256.362962)
				)
			)
		)
	)
	(footprint ""
		(layer "F.Cu")
		(at 29.541978 -305.648106 -135)
		(property "Reference" "R1241"
			(at 0 0 225)
			(layer "F.SilkS")
			(hide yes)
			(effects
				(font
					(size 1.27 1.27)
				)
			)
		)
		(property "Value" ""
			(at 0 0 225)
			(layer "F.Fab")
			(effects
				(font
					(size 1.27 1.27)
				)
			)
		)
		(duplicate_pad_numbers_are_jumpers no)
		(fp_line
			(start 0.787389 0.406267)
			(end -0.787389 0.406267)
			(stroke
				(width 0.1524)
				(type default)
			)
			(layer "F.SilkS")
		)
		(fp_line
			(start 0.787389 -0.406267)
			(end 0.787389 0.406267)
			(stroke
				(width 0.1524)
				(type default)
			)
			(layer "F.SilkS")
		)
		(fp_line
			(start -0.787389 0.406267)
			(end -0.787389 -0.406267)
			(stroke
				(width 0.1524)
				(type default)
			)
			(layer "F.SilkS")
		)
		(fp_line
			(start -0.787389 -0.406267)
			(end 0.787389 -0.406267)
			(stroke
				(width 0.1524)
				(type default)
			)
			(layer "F.SilkS")
		)
		(fp_line
			(start 0.679446 0.30479)
			(end 0.120515 0.30479)
			(stroke
				(width 0.1)
				(type default)
			)
			(layer "F.Fab")
		)
		(fp_line
			(start 0.120515 0.30479)
			(end 0.120335 0.279466)
			(stroke
				(width 0.1)
				(type default)
			)
			(layer "F.Fab")
		)
		(fp_line
			(start 0.120335 0.279466)
			(end -0.120695 0.279466)
			(stroke
				(width 0.1)
				(type default)
			)
			(layer "F.Fab")
		)
		(fp_line
			(start 0.679446 -0.30479)
			(end 0.679446 0.30479)
			(stroke
				(width 0.1)
				(type default)
			)
			(layer "F.Fab")
		)
		(fp_line
			(start -0.120515 0.30479)
			(end -0.679446 0.30479)
			(stroke
				(width 0.1)
				(type default)
			)
			(layer "F.Fab")
		)
		(fp_line
			(start -0.120695 0.279466)
			(end -0.120515 0.30479)
			(stroke
				(width 0.1)
				(type default)
			)
			(layer "F.Fab")
		)
		(fp_line
			(start 0.120695 -0.279466)
			(end 0.120515 -0.30479)
			(stroke
				(width 0.1)
				(type default)
			)
			(layer "F.Fab")
		)
		(fp_line
			(start 0.120515 -0.30479)
			(end 0.679446 -0.30479)
			(stroke
				(width 0.1)
				(type default)
			)
			(layer "F.Fab")
		)
		(fp_line
			(start -0.679446 0.30479)
			(end -0.679446 -0.305149)
			(stroke
				(width 0.1)
				(type default)
			)
			(layer "F.Fab")
		)
		(fp_line
			(start -0.120695 -0.279466)
			(end 0.120695 -0.279466)
			(stroke
				(width 0.1)
				(type default)
			)
			(layer "F.Fab")
		)
		(fp_line
			(start -0.120695 -0.304969)
			(end -0.120695 -0.279466)
			(stroke
				(width 0.1)
				(type default)
			)
			(layer "F.Fab")
		)
		(fp_line
			(start -0.679446 -0.305149)
			(end -0.120695 -0.304969)
			(stroke
				(width 0.1)
				(type default)
			)
			(layer "F.Fab")
		)
		(pad "1" smd circle
			(at -0.40005 0 225)
			(size 0 0)
			(layers "F.Cu" "F.Mask" "F.Paste")
			(net "PEX0_DFT_IDDT")
		)
		(pad "2" smd circle
			(at 0.40005 0 225)
			(size 0 0)
			(layers "F.Cu" "F.Mask" "F.Paste")
			(net "P1V8_PEX")
		)
	)
)
